# T6G (Grand Teton) — schematic netlist excerpt (pin names and nets, part order shuffled) for the footprints in the layout excerpt that follows; sources: Cadence DE-HDL packaged netlist, KiCad conversion of 04192023_DAF0TMB3IC0_F0TG_MB_C_brd_V02_OCP.brd

C1098  Q_CAP_DIFFBUS  DIFF BUS_0.22UF 6.3V 20% X6S  pkg C0201  page 67 : \1\ = P3E_CPU1_P4_TX_C_DP<3> ; \2\ = P3E_CPU1_P4_TX_DP<3>
R957  Q_RES  33 5% CHIP  pkg 0402LF  page 81 : A = FM_RST_PERST_SCM_R_N ; B = FM_RST_PERST_SCM_N

(kicad_pcb
	(version 20260206)
	(generator "pcbnew")
	(generator_version "10.0")
	(general
		(thickness 1.6)
		(legacy_teardrops no)
	)
	(paper "A4")
	(title_block
		(title "04192023_DAF0TMB3IC0_F0TG_MB_C_brd_V02_OCP.brd")
		(comment 1 "Grand Teton / footprints 2846-2847 of 8354")
	)
	(layers
		(0 "F.Cu" signal "TOP")
		(4 "In1.Cu" signal "GND")
		(6 "In2.Cu" signal "IN1")
		(8 "In3.Cu" signal "GND1")
		(10 "In4.Cu" signal "IN2")
		(12 "In5.Cu" signal "GND2")
		(14 "In6.Cu" signal "IN3")
		(16 "In7.Cu" signal "GND3")
		(18 "In8.Cu" signal "VCC")
		(20 "In9.Cu" signal "VCC1")
		(22 "In10.Cu" signal "GND4")
		(24 "In11.Cu" signal "IN4")
		(26 "In12.Cu" signal "GND5")
		(28 "In13.Cu" signal "IN5")
		(30 "In14.Cu" signal "GND6")
		(32 "In15.Cu" signal "IN6")
		(34 "In16.Cu" signal "GND7")
		(2 "B.Cu" signal "BOTTOM")
		(9 "F.Adhes" user "F.Adhesive")
		(11 "B.Adhes" user "B.Adhesive")
		(13 "F.Paste" user "Package Geometry/Pastemask Top")
		(15 "B.Paste" user "Package Geometry/Pastemask Bottom")
		(5 "F.SilkS" user "Ref Des/Silkscreen Top")
		(7 "B.SilkS" user "Ref Des/Silkscreen Bottom")
		(1 "F.Mask" user "Board Geometry/Soldermask Top")
		(3 "B.Mask" user "Board Geometry/Soldermask Bottom")
		(17 "Dwgs.User" user "User.Drawings")
		(19 "Cmts.User" user "User.Comments")
		(21 "Eco1.User" user "User.Eco1")
		(23 "Eco2.User" user "User.Eco2")
		(25 "Edge.Cuts" user "Board Geometry/Outline")
		(27 "Margin" user)
		(31 "F.CrtYd" user "Package Geometry/Place Bound Top")
		(29 "B.CrtYd" user "Package Geometry/Place Bound Bottom")
		(35 "F.Fab" user "Ref Des/Assembly Top")
		(33 "B.Fab" user "Ref Des/Assembly Bottom")
	)
	(footprint ""
		(layer "F.Cu")
		(at 197.269608 -116.673376)
		(property "Reference" "R957"
			(at 0 0 0)
			(layer "F.SilkS")
			(hide yes)
			(effects
				(font
					(size 1.27 1.27)
				)
			)
		)
		(property "Value" ""
			(at 0 0 0)
			(layer "F.Fab")
			(effects
				(font
					(size 1.27 1.27)
				)
			)
		)
		(duplicate_pad_numbers_are_jumpers no)
		(fp_line
			(start -0.7874 -0.4064)
			(end 0.7874 -0.4064)
			(stroke
				(width 0.1524)
				(type default)
			)
			(layer "F.SilkS")
		)
		(fp_line
			(start -0.7874 0.4064)
			(end -0.7874 -0.4064)
			(stroke
				(width 0.1524)
				(type default)
			)
			(layer "F.SilkS")
		)
		(fp_line
			(start 0.7874 -0.4064)
			(end 0.7874 0.4064)
			(stroke
				(width 0.1524)
				(type default)
			)
			(layer "F.SilkS")
		)
		(fp_line
			(start 0.7874 0.4064)
			(end -0.7874 0.4064)
			(stroke
				(width 0.1524)
				(type default)
			)
			(layer "F.SilkS")
		)
		(fp_line
			(start -0.67945 -0.305054)
			(end -0.12065 -0.305054)
			(stroke
				(width 0.1)
				(type default)
			)
			(layer "F.Fab")
		)
		(fp_line
			(start -0.67945 0.3048)
			(end -0.67945 -0.305054)
			(stroke
				(width 0.1)
				(type default)
			)
			(layer "F.Fab")
		)
		(fp_line
			(start -0.12065 -0.305054)
			(end -0.12065 -0.2794)
			(stroke
				(width 0.1)
				(type default)
			)
			(layer "F.Fab")
		)
		(fp_line
			(start -0.12065 -0.2794)
			(end 0.12065 -0.2794)
			(stroke
				(width 0.1)
				(type default)
			)
			(layer "F.Fab")
		)
		(fp_line
			(start -0.12065 0.2794)
			(end -0.12065 0.3048)
			(stroke
				(width 0.1)
				(type default)
			)
			(layer "F.Fab")
		)
		(fp_line
			(start -0.12065 0.3048)
			(end -0.67945 0.3048)
			(stroke
				(width 0.1)
				(type default)
			)
			(layer "F.Fab")
		)
		(fp_line
			(start 0.120396 0.2794)
			(end -0.12065 0.2794)
			(stroke
				(width 0.1)
				(type default)
			)
			(layer "F.Fab")
		)
		(fp_line
			(start 0.120396 0.3048)
			(end 0.120396 0.2794)
			(stroke
				(width 0.1)
				(type default)
			)
			(layer "F.Fab")
		)
		(fp_line
			(start 0.12065 -0.3048)
			(end 0.67945 -0.3048)
			(stroke
				(width 0.1)
				(type default)
			)
			(layer "F.Fab")
		)
		(fp_line
			(start 0.12065 -0.2794)
			(end 0.12065 -0.3048)
			(stroke
				(width 0.1)
				(type default)
			)
			(layer "F.Fab")
		)
		(fp_line
			(start 0.67945 -0.3048)
			(end 0.67945 0.3048)
			(stroke
				(width 0.1)
				(type default)
			)
			(layer "F.Fab")
		)
		(fp_line
			(start 0.67945 0.3048)
			(end 0.120396 0.3048)
			(stroke
				(width 0.1)
				(type default)
			)
			(layer "F.Fab")
		)
		(pad "1" smd circle
			(at -0.40005 0)
			(size 0 0)
			(layers "F.Cu" "F.Mask" "F.Paste")
			(net "FM_RST_PERST_SCM_R_N")
		)
		(pad "2" smd circle
			(at 0.40005 0)
			(size 0 0)
			(layers "F.Cu" "F.Mask" "F.Paste")
			(net "FM_RST_PERST_SCM_N")
		)
	)
	(footprint ""
		(layer "F.Cu")
		(at 180.528468 -53.065934)
		(property "Reference" "C1098"
			(at 0 0 0)
			(layer "F.SilkS")
			(hide yes)
			(effects
				(font
					(size 1.27 1.27)
				)
			)
		)
		(property "Value" ""
			(at 0 0 0)
			(layer "F.Fab")
			(effects
				(font
					(size 1.27 1.27)
				)
			)
		)
		(duplicate_pad_numbers_are_jumpers no)
		(fp_line
			(start -0.299974 -0.150114)
			(end 0.299974 -0.150114)
			(stroke
				(width 0.1)
				(type default)
			)
			(layer "F.Fab")
		)
		(fp_line
			(start -0.299974 0.150114)
			(end -0.299974 -0.150114)
			(stroke
				(width 0.1)
				(type default)
			)
			(layer "F.Fab")
		)
		(fp_line
			(start 0.299974 -0.150114)
			(end 0.299974 0.150114)
			(stroke
				(width 0.1)
				(type default)
			)
			(layer "F.Fab")
		)
		(fp_line
			(start 0.299974 0.150114)
			(end -0.299974 0.150114)
			(stroke
				(width 0.1)
				(type default)
			)
			(layer "F.Fab")
		)
		(pad "1" smd rect
			(at -0.2667 0)
			(size 0.3048 0.381)
			(layers "F.Cu" "F.Mask" "F.Paste")
			(net "P3E_CPU1_P4_TX_C_DP<3>")
		)
		(pad "2" smd rect
			(at 0.2667 0)
			(size 0.3048 0.381)
			(layers "F.Cu" "F.Mask" "F.Paste")
			(net "P3E_CPU1_P4_TX_DP<3>")
		)
	)
)
